(kicad_pcb
	(version 20260206)
	(generator "pcbnew")
	(generator_version "10.0")
	(general
		(thickness 1.6)
		(legacy_teardrops no)
	)
	(paper "A4")
	(title_block
		(title "Bryce Canyon_F.DPB_16315-1-OCP.brd")
		(comment 1 "Bryce Canyon / footprints 1510-1517 of 2223")
	)
	(layers
		(0 "F.Cu" signal "TOP")
		(4 "In1.Cu" signal "L2GND")
		(6 "In2.Cu" signal "L3")
		(8 "In3.Cu" signal "L4GND")
		(10 "In4.Cu" signal "L5")
		(12 "In5.Cu" signal "L6VCC")
		(14 "In6.Cu" signal "L7VCC")
		(16 "In7.Cu" signal "L8")
		(18 "In8.Cu" signal "L9GND")
		(20 "In9.Cu" signal "L10")
		(22 "In10.Cu" signal "L11GND")
		(2 "B.Cu" signal "BOTTOM")
		(9 "F.Adhes" user "F.Adhesive")
		(11 "B.Adhes" user "B.Adhesive")
		(13 "F.Paste" user "Package Geometry/Pastemask Top")
		(15 "B.Paste" user "Package Geometry/Pastemask Bottom")
		(5 "F.SilkS" user "Ref Des/Silkscreen Top")
		(7 "B.SilkS" user "Ref Des/Silkscreen Bottom")
		(1 "F.Mask" user "Board Geometry/Soldermask Top")
		(3 "B.Mask" user "Board Geometry/Soldermask Bottom")
		(17 "Dwgs.User" user "User.Drawings")
		(19 "Cmts.User" user "User.Comments")
		(21 "Eco1.User" user "User.Eco1")
		(23 "Eco2.User" user "User.Eco2")
		(25 "Edge.Cuts" user "Board Geometry/Outline")
		(27 "Margin" user)
		(31 "F.CrtYd" user "Package Geometry/Place Bound Top")
		(29 "B.CrtYd" user "Package Geometry/Place Bound Bottom")
		(35 "F.Fab" user "Ref Des/Assembly Top")
		(33 "B.Fab" user "Ref Des/Assembly Bottom")
	)
	(footprint ""
		(layer "F.Cu")
		(at 272.8976 15.273528)
		(property "Reference" "Q4"
			(at 0 0 0)
			(layer "F.SilkS")
			(hide yes)
			(effects
				(font
					(size 1.27 1.27)
				)
			)
		)
		(property "Value" "2N7002KDW-GP"
			(at -2.3622 -8.2042 0)
			(unlocked yes)
			(layer "F.Fab")
			(hide yes)
			(effects
				(font
					(size 1.016 1.016)
					(thickness 0.1524)
				)
			)
		)
		(property "Device Type" "SOT-363H44"
			(at -2.3622 -10.1092 0)
			(unlocked yes)
			(layer "F.Fab")
			(hide yes)
			(effects
				(font
					(size 1.016 1.016)
					(thickness 0.1524)
				)
			)
		)
		(duplicate_pad_numbers_are_jumpers no)
		(fp_line
			(start -1.4478 -1.7018)
			(end -1.4478 1.7018)
			(stroke
				(width 0.1524)
				(type default)
			)
			(layer "F.SilkS")
		)
		(fp_line
			(start -1.4478 1.7018)
			(end 1.4478 1.7018)
			(stroke
				(width 0.1524)
				(type default)
			)
			(layer "F.SilkS")
		)
		(fp_line
			(start -1.27 1.524)
			(end -1.27 0.6604)
			(stroke
				(width 0.4826)
				(type default)
			)
			(layer "F.SilkS")
		)
		(fp_line
			(start 1.4478 -1.7018)
			(end -1.4478 -1.7018)
			(stroke
				(width 0.1524)
				(type default)
			)
			(layer "F.SilkS")
		)
		(fp_line
			(start 1.4478 1.7018)
			(end 1.4478 -1.7018)
			(stroke
				(width 0.1524)
				(type default)
			)
			(layer "F.SilkS")
		)
		(fp_poly
			(pts
				(xy -1.524 -1.778) (xy 1.524 -1.778) (xy 1.524 1.778) (xy -1.524 1.778)
			)
			(stroke
				(width 0)
				(type default)
			)
			(fill no)
			(layer "F.CrtYd")
		)
		(fp_poly
			(pts
				(xy -1.524 -1.778) (xy 1.524 -1.778) (xy 1.524 1.778) (xy -1.524 1.778)
			)
			(stroke
				(width 0)
				(type default)
			)
			(fill no)
			(layer "F.Fab")
		)
		(pad "1" smd rect
			(at -0.65024 0.9398)
			(size 0.4064 1.016)
			(layers "F.Cu" "F.Mask" "F.Paste")
			(net "GND")
		)
		(pad "2" smd rect
			(at 0 0.9398)
			(size 0.4064 1.016)
			(layers "F.Cu" "F.Mask" "F.Paste")
			(net "SCC_B_FAULT_LED")
		)
		(pad "3" smd rect
			(at 0.65024 0.9398)
			(size 0.4064 1.016)
			(layers "F.Cu" "F.Mask" "F.Paste")
			(net "ENCL_FAULT_LED_B")
		)
		(pad "4" smd rect
			(at 0.65024 -0.9398)
			(size 0.4064 1.016)
			(layers "F.Cu" "F.Mask" "F.Paste")
			(net "GND")
		)
		(pad "5" smd rect
			(at 0 -0.9398)
			(size 0.4064 1.016)
			(layers "F.Cu" "F.Mask" "F.Paste")
			(net "IOM_B_FAULT_LED")
		)
		(pad "6" smd rect
			(at -0.65024 -0.9398)
			(size 0.4064 1.016)
			(layers "F.Cu" "F.Mask" "F.Paste")
			(net "ENCL_FAULT_LED_B")
		)
	)
	(footprint ""
		(layer "F.Cu")
		(at 232.3084 -231.3178 180)
		(property "Reference" "R67"
			(at 0 0 180)
			(layer "F.SilkS")
			(hide yes)
			(effects
				(font
					(size 1.27 1.27)
				)
			)
		)
		(property "Value" "4K7R2F-GP"
			(at 0.064008 -3.993896 180)
			(unlocked yes)
			(layer "F.Fab")
			(hide yes)
			(effects
				(font
					(size 1.016 1.016)
					(thickness 0.1524)
				)
			)
		)
		(property "Device Type" "R402H16"
			(at 0.064008 -5.517896 180)
			(unlocked yes)
			(layer "F.Fab")
			(hide yes)
			(effects
				(font
					(size 1.016 1.016)
					(thickness 0.1524)
				)
			)
		)
		(duplicate_pad_numbers_are_jumpers no)
		(fp_line
			(start 0.508 -0.9398)
			(end -0.508 -0.9398)
			(stroke
				(width 0.1524)
				(type default)
			)
			(layer "F.SilkS")
		)
		(fp_line
			(start -0.508 -0.9398)
			(end -0.508 0.9398)
			(stroke
				(width 0.1524)
				(type default)
			)
			(layer "F.SilkS")
		)
		(fp_rect
			(start -0.508 0.9398)
			(end 0.508 -0.9398)
			(stroke
				(width 0)
				(type default)
			)
			(fill no)
			(layer "F.CrtYd")
		)
		(fp_rect
			(start -0.508 0.9398)
			(end 0.508 -0.9398)
			(stroke
				(width 0)
				(type default)
			)
			(fill no)
			(layer "F.Fab")
		)
		(pad "1" smd custom
			(at 0 -0.4445 180)
			(size 0.1397 0.1397)
			(layers "F.Cu" "F.Mask" "F.Paste")
			(net "P3V3_STBY_A")
			(options
				(clearance outline)
				(anchor circle)
			)
			(primitives
				(gr_poly
					(pts
						(arc
							(start -0.1778 -0.2794)
							(mid -0.249642 -0.249642)
							(end -0.2794 -0.1778)
						)
						(arc
							(start -0.2794 0.1778)
							(mid -0.249642 0.249642)
							(end -0.1778 0.2794)
						)
						(arc
							(start 0.1778 0.2794)
							(mid 0.249642 0.249642)
							(end 0.2794 0.1778)
						)
						(arc
							(start 0.2794 -0.1778)
							(mid 0.249642 -0.249642)
							(end 0.1778 -0.2794)
						)
					)
					(width 0)
					(fill yes)
				)
			)
		)
		(pad "2" smd custom
			(at 0 0.4445 180)
			(size 0.1397 0.1397)
			(layers "F.Cu" "F.Mask" "F.Paste")
			(net "IO_EXP1_A0")
			(options
				(clearance outline)
				(anchor circle)
			)
			(primitives
				(gr_poly
					(pts
						(arc
							(start -0.1778 -0.2794)
							(mid -0.249642 -0.249642)
							(end -0.2794 -0.1778)
						)
						(arc
							(start -0.2794 0.1778)
							(mid -0.249642 0.249642)
							(end -0.1778 0.2794)
						)
						(arc
							(start 0.1778 0.2794)
							(mid 0.249642 0.249642)
							(end 0.2794 0.1778)
						)
						(arc
							(start 0.2794 -0.1778)
							(mid 0.249642 -0.249642)
							(end 0.1778 -0.2794)
						)
					)
					(width 0)
					(fill yes)
				)
			)
		)
	)
	(footprint ""
		(layer "F.Cu")
		(at 150.565866 -145.372074 180)
		(property "Reference" "R1057"
			(at 0 0 180)
			(layer "F.SilkS")
			(hide yes)
			(effects
				(font
					(size 1.27 1.27)
				)
			)
		)
		(property "Value" "137KR2F-1-GP"
			(at 0.064008 -3.993896 180)
			(unlocked yes)
			(layer "F.Fab")
			(hide yes)
			(effects
				(font
					(size 1.016 1.016)
					(thickness 0.1524)
				)
			)
		)
		(property "Device Type" "R402H16"
			(at 0.064008 -5.517896 180)
			(unlocked yes)
			(layer "F.Fab")
			(hide yes)
			(effects
				(font
					(size 1.016 1.016)
					(thickness 0.1524)
				)
			)
		)
		(duplicate_pad_numbers_are_jumpers no)
		(fp_line
			(start 0.508 -0.9398)
			(end -0.508 -0.9398)
			(stroke
				(width 0.1524)
				(type default)
			)
			(layer "F.SilkS")
		)
		(fp_line
			(start -0.508 -0.9398)
			(end -0.508 0.9398)
			(stroke
				(width 0.1524)
				(type default)
			)
			(layer "F.SilkS")
		)
		(fp_rect
			(start -0.508 0.9398)
			(end 0.508 -0.9398)
			(stroke
				(width 0)
				(type default)
			)
			(fill no)
			(layer "F.CrtYd")
		)
		(fp_rect
			(start -0.508 0.9398)
			(end 0.508 -0.9398)
			(stroke
				(width 0)
				(type default)
			)
			(fill no)
			(layer "F.Fab")
		)
		(pad "1" smd custom
			(at 0 -0.4445 180)
			(size 0.1397 0.1397)
			(layers "F.Cu" "F.Mask" "F.Paste")
			(net "MB0_PSET_R")
			(options
				(clearance outline)
				(anchor circle)
			)
			(primitives
				(gr_poly
					(pts
						(arc
							(start -0.1778 -0.2794)
							(mid -0.249642 -0.249642)
							(end -0.2794 -0.1778)
						)
						(arc
							(start -0.2794 0.1778)
							(mid -0.249642 0.249642)
							(end -0.1778 0.2794)
						)
						(arc
							(start 0.1778 0.2794)
							(mid 0.249642 0.249642)
							(end 0.2794 0.1778)
						)
						(arc
							(start 0.2794 -0.1778)
							(mid 0.249642 -0.249642)
							(end 0.1778 -0.2794)
						)
					)
					(width 0)
					(fill yes)
				)
			)
		)
		(pad "2" smd custom
			(at 0 0.4445 180)
			(size 0.1397 0.1397)
			(layers "F.Cu" "F.Mask" "F.Paste")
			(net "AGND_CURRENT_MONOA")
			(options
				(clearance outline)
				(anchor circle)
			)
			(primitives
				(gr_poly
					(pts
						(arc
							(start -0.1778 -0.2794)
							(mid -0.249642 -0.249642)
							(end -0.2794 -0.1778)
						)
						(arc
							(start -0.2794 0.1778)
							(mid -0.249642 0.249642)
							(end -0.1778 0.2794)
						)
						(arc
							(start 0.1778 0.2794)
							(mid 0.249642 0.249642)
							(end 0.2794 0.1778)
						)
						(arc
							(start 0.2794 -0.1778)
							(mid 0.249642 -0.249642)
							(end 0.1778 -0.2794)
						)
					)
					(width 0)
					(fill yes)
				)
			)
		)
	)
	(footprint ""
		(layer "F.Cu")
		(at 30.149038 -252.730254 -90)
		(property "Reference" "R1212"
			(at 0 0 270)
			(layer "F.SilkS")
			(hide yes)
			(effects
				(font
					(size 1.27 1.27)
				)
			)
		)
		(property "Value" "200KR2F-L-GP"
			(at 0.064008 -3.993896 270)
			(unlocked yes)
			(layer "F.Fab")
			(hide yes)
			(effects
				(font
					(size 1.016 1.016)
					(thickness 0.1524)
				)
			)
		)
		(property "Device Type" "R402H16"
			(at 0.064008 -5.517896 270)
			(unlocked yes)
			(layer "F.Fab")
			(hide yes)
			(effects
				(font
					(size 1.016 1.016)
					(thickness 0.1524)
				)
			)
		)
		(duplicate_pad_numbers_are_jumpers no)
		(fp_line
			(start -0.508 -0.9398)
			(end -0.508 0.9398)
			(stroke
				(width 0.1524)
				(type default)
			)
			(layer "F.SilkS")
		)
		(fp_line
			(start 0.508 -0.9398)
			(end -0.508 -0.9398)
			(stroke
				(width 0.1524)
				(type default)
			)
			(layer "F.SilkS")
		)
		(fp_rect
			(start -0.508 0.9398)
			(end 0.508 -0.9398)
			(stroke
				(width 0)
				(type default)
			)
			(fill no)
			(layer "F.CrtYd")
		)
		(fp_rect
			(start -0.508 0.9398)
			(end 0.508 -0.9398)
			(stroke
				(width 0)
				(type default)
			)
			(fill no)
			(layer "F.Fab")
		)
		(pad "1" smd custom
			(at 0 -0.4445 270)
			(size 0.1397 0.1397)
			(layers "F.Cu" "F.Mask" "F.Paste")
			(net "P5V_A_MODE")
			(options
				(clearance outline)
				(anchor circle)
			)
			(primitives
				(gr_poly
					(pts
						(arc
							(start -0.1778 -0.2794)
							(mid -0.249642 -0.249642)
							(end -0.2794 -0.1778)
						)
						(arc
							(start -0.2794 0.1778)
							(mid -0.249642 0.249642)
							(end -0.1778 0.2794)
						)
						(arc
							(start 0.1778 0.2794)
							(mid 0.249642 0.249642)
							(end 0.2794 0.1778)
						)
						(arc
							(start 0.2794 -0.1778)
							(mid 0.249642 -0.249642)
							(end 0.1778 -0.2794)
						)
					)
					(width 0)
					(fill yes)
				)
			)
		)
		(pad "2" smd custom
			(at 0 0.4445 270)
			(size 0.1397 0.1397)
			(layers "F.Cu" "F.Mask" "F.Paste")
			(net "P5V_A_1_PGOOD")
			(options
				(clearance outline)
				(anchor circle)
			)
			(primitives
				(gr_poly
					(pts
						(arc
							(start -0.1778 -0.2794)
							(mid -0.249642 -0.249642)
							(end -0.2794 -0.1778)
						)
						(arc
							(start -0.2794 0.1778)
							(mid -0.249642 0.249642)
							(end -0.1778 0.2794)
						)
						(arc
							(start 0.1778 0.2794)
							(mid 0.249642 0.249642)
							(end 0.2794 0.1778)
						)
						(arc
							(start 0.2794 -0.1778)
							(mid 0.249642 -0.249642)
							(end 0.1778 -0.2794)
						)
					)
					(width 0)
					(fill yes)
				)
			)
		)
	)
	(footprint ""
		(layer "F.Cu")
		(at 478.282 -48.067976)
		(property "Reference" "C497"
			(at 0 0 0)
			(layer "F.SilkS")
			(hide yes)
			(effects
				(font
					(size 1.27 1.27)
				)
			)
		)
		(property "Value" "SCD01U50V2KX-1GP"
			(at 1.1811 -2.7051 0)
			(unlocked yes)
			(layer "F.Fab")
			(hide yes)
			(effects
				(font
					(size 1.016 1.016)
					(thickness 0.1524)
				)
			)
		)
		(property "Device Type" "C402H22"
			(at 1.1811 -4.2291 0)
			(unlocked yes)
			(layer "F.Fab")
			(hide yes)
			(effects
				(font
					(size 1.016 1.016)
					(thickness 0.1524)
				)
			)
		)
		(duplicate_pad_numbers_are_jumpers no)
		(fp_rect
			(start -0.4318 0.9525)
			(end 0.4318 -0.9525)
			(stroke
				(width 0)
				(type default)
			)
			(fill no)
			(layer "F.CrtYd")
		)
		(fp_rect
			(start -0.4318 0.9525)
			(end 0.4318 -0.9525)
			(stroke
				(width 0)
				(type default)
			)
			(fill no)
			(layer "F.Fab")
		)
		(pad "1" smd custom
			(at 0 -0.4445)
			(size 0.1524 0.1524)
			(layers "F.Cu" "F.Mask" "F.Paste")
			(net "HDD_PRSNT_35")
			(options
				(clearance outline)
				(anchor circle)
			)
			(primitives
				(gr_poly
					(pts
						(arc
							(start 0.3048 -0.2032)
							(mid 0.275042 -0.275042)
							(end 0.2032 -0.3048)
						)
						(arc
							(start -0.2032 -0.3048)
							(mid -0.275042 -0.275042)
							(end -0.3048 -0.2032)
						)
						(arc
							(start -0.3048 0.2032)
							(mid -0.275042 0.275042)
							(end -0.2032 0.3048)
						)
						(arc
							(start 0.2032 0.3048)
							(mid 0.275042 0.275042)
							(end 0.3048 0.2032)
						)
					)
					(width 0)
					(fill yes)
				)
			)
		)
		(pad "2" smd custom
			(at 0 0.4445)
			(size 0.1524 0.1524)
			(layers "F.Cu" "F.Mask" "F.Paste")
			(net "GND")
			(options
				(clearance outline)
				(anchor circle)
			)
			(primitives
				(gr_poly
					(pts
						(arc
							(start 0.3048 -0.2032)
							(mid 0.275042 -0.275042)
							(end 0.2032 -0.3048)
						)
						(arc
							(start -0.2032 -0.3048)
							(mid -0.275042 -0.275042)
							(end -0.3048 -0.2032)
						)
						(arc
							(start -0.3048 0.2032)
							(mid -0.275042 0.275042)
							(end -0.2032 0.3048)
						)
						(arc
							(start 0.2032 0.3048)
							(mid 0.275042 0.275042)
							(end 0.3048 0.2032)
						)
					)
					(width 0)
					(fill yes)
				)
			)
		)
	)
	(footprint ""
		(layer "F.Cu")
		(at 474.853 -47.686976)
		(property "Reference" "R939"
			(at 0 0 0)
			(layer "F.SilkS")
			(hide yes)
			(effects
				(font
					(size 1.27 1.27)
				)
			)
		)
		(property "Value" "220R3F-1-GP"
			(at -0.0254 -2.5146 0)
			(unlocked yes)
			(layer "F.Fab")
			(hide yes)
			(effects
				(font
					(size 1.016 1.016)
					(thickness 0.1524)
				)
			)
		)
		(property "Device Type" "R603H22"
			(at -0.0254 -4.0386 0)
			(unlocked yes)
			(layer "F.Fab")
			(hide yes)
			(effects
				(font
					(size 1.016 1.016)
					(thickness 0.1524)
				)
			)
		)
		(duplicate_pad_numbers_are_jumpers no)
		(fp_line
			(start -0.4826 0)
			(end -0.2032 0)
			(stroke
				(width 0.2032)
				(type default)
			)
			(layer "F.SilkS")
		)
		(fp_line
			(start 0.2032 0)
			(end 0.4826 0)
			(stroke
				(width 0.2032)
				(type default)
			)
			(layer "F.SilkS")
		)
		(fp_rect
			(start -0.5842 1.3335)
			(end 0.5842 -1.3335)
			(stroke
				(width 0)
				(type default)
			)
			(fill no)
			(layer "F.CrtYd")
		)
		(fp_rect
			(start -0.5842 1.3335)
			(end 0.5842 -1.3335)
			(stroke
				(width 0)
				(type default)
			)
			(fill no)
			(layer "F.Fab")
		)
		(pad "1" smd custom
			(at 0 -0.762)
			(size 0.2159 0.2159)
			(layers "F.Cu" "F.Mask" "F.Paste")
			(net "HDD_PRSNT_35")
			(options
				(clearance outline)
				(anchor circle)
			)
			(primitives
				(gr_poly
					(pts
						(arc
							(start -0.3302 -0.4318)
							(mid -0.402042 -0.402042)
							(end -0.4318 -0.3302)
						)
						(arc
							(start -0.4318 0.3302)
							(mid -0.402042 0.402042)
							(end -0.3302 0.4318)
						)
						(arc
							(start 0.3302 0.4318)
							(mid 0.402042 0.402042)
							(end 0.4318 0.3302)
						)
						(arc
							(start 0.4318 -0.3302)
							(mid 0.402042 -0.402042)
							(end 0.3302 -0.4318)
						)
					)
					(width 0)
					(fill yes)
				)
			)
		)
		(pad "2" smd custom
			(at 0 0.762)
			(size 0.2159 0.2159)
			(layers "F.Cu" "F.Mask" "F.Paste")
			(net "DRIVE_A_35_INS")
			(options
				(clearance outline)
				(anchor circle)
			)
			(primitives
				(gr_poly
					(pts
						(arc
							(start -0.3302 -0.4318)
							(mid -0.402042 -0.402042)
							(end -0.4318 -0.3302)
						)
						(arc
							(start -0.4318 0.3302)
							(mid -0.402042 0.402042)
							(end -0.3302 0.4318)
						)
						(arc
							(start 0.3302 0.4318)
							(mid 0.402042 0.402042)
							(end 0.4318 0.3302)
						)
						(arc
							(start 0.4318 -0.3302)
							(mid 0.402042 -0.402042)
							(end 0.3302 -0.4318)
						)
					)
					(width 0)
					(fill yes)
				)
			)
		)
	)
	(footprint ""
		(layer "F.Cu")
		(at 337.38693 -17.368266 180)
		(property "Reference" "U29"
			(at 0 0 180)
			(layer "F.SilkS")
			(hide yes)
			(effects
				(font
					(size 1.27 1.27)
				)
			)
		)
		(property "Value" "74LVC1G32DC-1GP"
			(at -2.3368 -8.6868 180)
			(unlocked yes)
			(layer "F.Fab")
			(hide yes)
			(effects
				(font
					(size 1.016 1.016)
					(thickness 0.1524)
				)
			)
		)
		(property "Device Type" "SC70-5H44"
			(at -2.3114 -10.414 180)
			(unlocked yes)
			(layer "F.Fab")
			(hide yes)
			(effects
				(font
					(size 1.016 1.016)
					(thickness 0.1524)
				)
			)
		)
		(duplicate_pad_numbers_are_jumpers no)
		(fp_line
			(start 1.3843 -1.8034)
			(end 1.3843 -1.1176)
			(stroke
				(width 0.3302)
				(type default)
			)
			(layer "F.SilkS")
		)
		(fp_line
			(start 1.27 1.7018)
			(end -1.27 1.7018)
			(stroke
				(width 0.1524)
				(type default)
			)
			(layer "F.SilkS")
		)
		(fp_line
			(start 1.27 -1.7018)
			(end 1.27 1.7018)
			(stroke
				(width 0.1524)
				(type default)
			)
			(layer "F.SilkS")
		)
		(fp_line
			(start 0.6604 -1.8034)
			(end 1.3843 -1.8034)
			(stroke
				(width 0.3302)
				(type default)
			)
			(layer "F.SilkS")
		)
		(fp_line
			(start -1.27 1.7018)
			(end -1.27 -1.7018)
			(stroke
				(width 0.1524)
				(type default)
			)
			(layer "F.SilkS")
		)
		(fp_line
			(start -1.27 -1.7018)
			(end 1.27 -1.7018)
			(stroke
				(width 0.1524)
				(type default)
			)
			(layer "F.SilkS")
		)
		(fp_rect
			(start -1.524 1.9558)
			(end 1.524 -1.9558)
			(stroke
				(width 0)
				(type default)
			)
			(fill no)
			(layer "F.CrtYd")
		)
		(fp_poly
			(pts
				(xy -1.524 -1.9558) (xy 1.524 -1.9558) (xy 1.524 1.9558) (xy -1.524 1.9558)
			)
			(stroke
				(width 0)
				(type default)
			)
			(fill no)
			(layer "F.Fab")
		)
		(pad "1" smd rect
			(at 0.65024 -0.8255 180)
			(size 0.4064 1.2192)
			(layers "F.Cu" "F.Mask" "F.Paste")
			(net "COMP_B_PRI_INS_N")
		)
		(pad "2" smd rect
			(at 0 -0.8255 180)
			(size 0.4064 1.2192)
			(layers "F.Cu" "F.Mask" "F.Paste")
			(net "COMP_B_SEC_INS_N")
		)
		(pad "3" smd rect
			(at -0.65024 -0.8255 180)
			(size 0.4064 1.2192)
			(layers "F.Cu" "F.Mask" "F.Paste")
			(net "GND")
		)
		(pad "4" smd rect
			(at -0.65024 0.8255 180)
			(size 0.4064 1.2192)
			(layers "F.Cu" "F.Mask" "F.Paste")
			(net "COMP_B_INS_N")
		)
		(pad "5" smd rect
			(at 0.65024 0.8255 180)
			(size 0.4064 1.2192)
			(layers "F.Cu" "F.Mask" "F.Paste")
			(net "P3V3_STBY_B")
		)
	)
	(footprint ""
		(layer "F.Cu")
		(at 255.386078 -9.720834 180)
		(property "Reference" "TP218"
			(at 0 0 180)
			(layer "F.SilkS")
			(hide yes)
			(effects
				(font
					(size 1.27 1.27)
				)
			)
		)
		(property "Value" "TPAD32-GP"
			(at -0.0508 -1.6764 180)
			(unlocked yes)
			(layer "F.Fab")
			(hide yes)
			(effects
				(font
					(size 1.016 1.016)
					(thickness 0.1524)
				)
			)
		)
		(property "Device Type" "TPAD32"
			(at -0.0508 -3.2004 180)
			(unlocked yes)
			(layer "F.Fab")
			(hide yes)
			(effects
				(font
					(size 1.016 1.016)
					(thickness 0.1524)
				)
			)
		)
		(duplicate_pad_numbers_are_jumpers no)
		(fp_poly
			(pts
				(arc
					(start -0.4064 0)
					(mid 0.4064 0)
					(end -0.4064 0)
				)
			)
			(stroke
				(width 0)
				(type default)
			)
			(fill no)
			(layer "F.CrtYd")
		)
		(fp_poly
			(pts
				(arc
					(start -0.7112 0)
					(mid 0.7112 0)
					(end -0.7112 0)
				)
			)
			(stroke
				(width 0)
				(type default)
			)
			(fill no)
			(layer "F.Fab")
		)
		(pad "1" smd circle
			(at 0 0 180)
			(size 0.8128 0.8128)
			(layers "F.Cu" "F.Mask" "F.Paste")
			(net "TP_COMP_A_NCSI_CRSDV")
		)
	)
)
